FILE_TYPE = CONNECTIVITY;
{Allegro Design Entry HDL 17.2-2016 S081 (4005846) 1/11/2022}
"PAGE_NUMBER" = 23;
0"NC";
1"GMI_CPU1_G0_CPU0_G2_TX_DP<15:0>";
2"GMI_CPU1_G0_CPU0_G2_TX_DN<15:0>";
3"P5E_CPU0_G3_RX_DP<15:0>";
4"P5E_CPU0_G3_RX_DN<15:0>";
5"P5E_CPU0_G3_TX_DP<15:0>";
6"GMI_CPU0_G2_CPU1_G0_TX_DP<15:0>";
7"GMI_CPU0_G2_CPU1_G0_TX_DN<15:0>";
8"P5E_CPU0_G3_TX_DN<15:0>";
9"P5E_CPU0_G3_TX_DN<3>";
10"P5E_CPU0_G3_TX_DP<5>";
11"P5E_CPU0_G3_TX_DN<6>";
12"P5E_CPU0_G3_TX_DN<10>";
13"P5E_CPU0_G3_TX_DP<10>";
14"P5E_CPU0_G3_RX_DP<8>";
15"P5E_CPU0_G3_TX_DP<3>";
16"P5E_CPU0_G3_TX_DN<7>";
17"P5E_CPU0_G3_TX_DN<5>";
18"P5E_CPU0_G3_TX_DP<6>";
19"P5E_CPU0_G3_TX_DN<4>";
20"P5E_CPU0_G3_TX_DP<4>";
21"P5E_CPU0_G3_TX_DN<2>";
22"P5E_CPU0_G3_TX_DP<2>";
23"P5E_CPU0_G3_TX_DN<1>";
24"P5E_CPU0_G3_TX_DN<0>";
25"P5E_CPU0_G3_TX_DP<7>";
26"P5E_CPU0_G3_TX_DP<9>";
27"GMI_CPU0_G2_CPU1_G0_TX_DN<15>";
28"GMI_CPU1_G0_CPU0_G2_TX_DN<10>";
29"GMI_CPU1_G0_CPU0_G2_TX_DP<10>";
30"P5E_CPU0_G3_TX_DP<0>";
31"P5E_CPU0_G3_TX_DP<1>";
32"P5E_CPU0_G3_RX_DP<5>";
33"P5E_CPU0_G3_RX_DN<4>";
34"P5E_CPU0_G3_RX_DP<4>";
35"P5E_CPU0_G3_RX_DN<5>";
36"P5E_CPU0_G3_RX_DP<0>";
37"P5E_CPU0_G3_RX_DN<6>";
38"P5E_CPU0_G3_RX_DP<6>";
39"P5E_CPU0_G3_RX_DN<3>";
40"P5E_CPU0_G3_RX_DP<3>";
41"P5E_CPU0_G3_RX_DN<2>";
42"P5E_CPU0_G3_RX_DP<2>";
43"P5E_CPU0_G3_RX_DN<1>";
44"P5E_CPU0_G3_RX_DP<1>";
45"P5E_CPU0_G3_RX_DN<0>";
46"P5E_CPU0_G3_RX_DN<8>";
47"P5E_CPU0_G3_RX_DN<9>";
48"P5E_CPU0_G3_RX_DN<11>";
49"GMI_CPU0_G2_CPU1_G0_TX_DN<8>";
50"GMI_CPU0_G2_CPU1_G0_TX_DN<10>";
51"GMI_CPU0_G2_CPU1_G0_TX_DN<12>";
52"GMI_CPU0_G2_CPU1_G0_TX_DN<14>";
53"GMI_CPU0_G2_CPU1_G0_TX_DN<9>";
54"GMI_CPU0_G2_CPU1_G0_TX_DN<11>";
55"GMI_CPU0_G2_CPU1_G0_TX_DN<13>";
56"GMI_CPU0_G2_CPU1_G0_TX_DN<0>";
57"GMI_CPU0_G2_CPU1_G0_TX_DN<1>";
58"GMI_CPU0_G2_CPU1_G0_TX_DN<2>";
59"GMI_CPU0_G2_CPU1_G0_TX_DN<3>";
60"GMI_CPU0_G2_CPU1_G0_TX_DN<4>";
61"GMI_CPU0_G2_CPU1_G0_TX_DN<5>";
62"GMI_CPU0_G2_CPU1_G0_TX_DN<6>";
63"GMI_CPU0_G2_CPU1_G0_TX_DN<7>";
64"GMI_CPU0_G2_CPU1_G0_TX_DP<1>";
65"GMI_CPU0_G2_CPU1_G0_TX_DP<0>";
66"GMI_CPU0_G2_CPU1_G0_TX_DP<2>";
67"GMI_CPU0_G2_CPU1_G0_TX_DP<3>";
68"GMI_CPU0_G2_CPU1_G0_TX_DP<4>";
69"GMI_CPU0_G2_CPU1_G0_TX_DP<5>";
70"GMI_CPU0_G2_CPU1_G0_TX_DP<6>";
71"GMI_CPU0_G2_CPU1_G0_TX_DP<7>";
72"GMI_CPU0_G2_CPU1_G0_TX_DP<8>";
73"GMI_CPU0_G2_CPU1_G0_TX_DP<10>";
74"GMI_CPU0_G2_CPU1_G0_TX_DP<12>";
75"GMI_CPU0_G2_CPU1_G0_TX_DP<9>";
76"GMI_CPU0_G2_CPU1_G0_TX_DP<11>";
77"GMI_CPU0_G2_CPU1_G0_TX_DP<14>";
78"GMI_CPU0_G2_CPU1_G0_TX_DP<13>";
79"GMI_CPU0_G2_CPU1_G0_TX_DP<15>";
80"P5E_CPU0_G3_TX_DN<8>";
81"P5E_CPU0_G3_TX_DP<8>";
82"P5E_CPU0_G3_TX_DN<14>";
83"P5E_CPU0_G3_TX_DN<11>";
84"P5E_CPU0_G3_TX_DN<15>";
85"P5E_CPU0_G3_TX_DN<12>";
86"P5E_CPU0_G3_TX_DN<13>";
87"P5E_CPU0_G3_TX_DN<9>";
88"P5E_CPU0_G3_TX_DP<13>";
89"P5E_CPU0_G3_TX_DP<11>";
90"P5E_CPU0_G3_TX_DP<14>";
91"P5E_CPU0_G3_TX_DP<12>";
92"P5E_CPU0_G3_TX_DP<15>";
93"GMI_CPU1_G0_CPU0_G2_TX_DP<14>";
94"GMI_CPU1_G0_CPU0_G2_TX_DN<14>";
95"GMI_CPU1_G0_CPU0_G2_TX_DN<13>";
96"GMI_CPU1_G0_CPU0_G2_TX_DP<15>";
97"GMI_CPU1_G0_CPU0_G2_TX_DN<15>";
98"GMI_CPU1_G0_CPU0_G2_TX_DP<0>";
99"GMI_CPU1_G0_CPU0_G2_TX_DP<1>";
100"GMI_CPU1_G0_CPU0_G2_TX_DP<2>";
101"GMI_CPU1_G0_CPU0_G2_TX_DN<0>";
102"GMI_CPU1_G0_CPU0_G2_TX_DP<3>";
103"GMI_CPU1_G0_CPU0_G2_TX_DN<1>";
104"GMI_CPU1_G0_CPU0_G2_TX_DP<4>";
105"GMI_CPU1_G0_CPU0_G2_TX_DN<2>";
106"GMI_CPU1_G0_CPU0_G2_TX_DP<5>";
107"GMI_CPU1_G0_CPU0_G2_TX_DN<3>";
108"GMI_CPU1_G0_CPU0_G2_TX_DN<4>";
109"P5E_CPU0_G3_RX_DP<11>";
110"P5E_CPU0_G3_RX_DN<10>";
111"P5E_CPU0_G3_RX_DP<10>";
112"P5E_CPU0_G3_RX_DN<15>";
113"P5E_CPU0_G3_RX_DP<15>";
114"P5E_CPU0_G3_RX_DN<14>";
115"P5E_CPU0_G3_RX_DP<14>";
116"P5E_CPU0_G3_RX_DN<13>";
117"P5E_CPU0_G3_RX_DN<12>";
118"P5E_CPU0_G3_RX_DP<13>";
119"P5E_CPU0_G3_RX_DP<12>";
120"P5E_CPU0_G3_RX_DP<9>";
121"P5E_CPU0_G3_RX_DN<7>";
122"P5E_CPU0_G3_RX_DP<7>";
123"GMI_CPU1_G0_CPU0_G2_TX_DP<13>";
124"GMI_CPU1_G0_CPU0_G2_TX_DN<12>";
125"GMI_CPU1_G0_CPU0_G2_TX_DP<12>";
126"GMI_CPU1_G0_CPU0_G2_TX_DN<11>";
127"GMI_CPU1_G0_CPU0_G2_TX_DP<11>";
128"GMI_CPU1_G0_CPU0_G2_TX_DN<9>";
129"GMI_CPU1_G0_CPU0_G2_TX_DP<9>";
130"GMI_CPU1_G0_CPU0_G2_TX_DN<8>";
131"GMI_CPU1_G0_CPU0_G2_TX_DP<8>";
132"GMI_CPU1_G0_CPU0_G2_TX_DN<7>";
133"GMI_CPU1_G0_CPU0_G2_TX_DP<7>";
134"GMI_CPU1_G0_CPU0_G2_TX_DN<6>";
135"GMI_CPU1_G0_CPU0_G2_TX_DP<6>";
136"GMI_CPU1_G0_CPU0_G2_TX_DN<5>";
%"GENOA_SP5"
"13","(-4775,5075)","0","pure_quanta","I215";
;
LOCATION"U25"
$SEC"13"
CDS_SEC"13"
PART_TYPE"SMLF"
VALUE"SOCKET6096_13568-001"
PART_NUMBER"DGA^6000030"
MATERIAL"IO"
CDS_LIB"pure_quanta"
NEEDS_NO_SIZE"TRUE"
CDS_LMAN_SYM_OUTLINE"-1100,950,1100,-950";
"G2_TXP0"
$PN"N23"65;
"G2_RXN7"
$PN"AC29"132;
"G2_RXN6"
$PN"AE29"134;
"G2_RXN5"
$PN"AG26"136;
"G2_RXP7"
$PN"AC30"133;
"G2_TXN7"
$PN"J30"63;
"G2_RXN4"
$PN"AC26"108;
"G2_RXP6"
$PN"AE30"135;
"G2_TXN6"
$PN"L27"62;
"G2_RXN3"
$PN"AE26"107;
"G2_RXP5"
$PN"AG27"106;
"G2_TXN5"
$PN"G27"61;
"G2_TXP7"
$PN"J29"71;
"G2_RXN2"
$PN"AG23"105;
"G2_RXP4"
$PN"AC27"104;
"G2_TXN4"
$PN"J27"60;
"G2_TXP6"
$PN"L26"70;
"G2_RXN1"
$PN"AC23"103;
"G2_RXP3"
$PN"AE27"102;
"G2_TXN3"
$PN"L24"59;
"G2_TXP5"
$PN"G26"69;
"G2_RXN0"
$PN"AE23"101;
"G2_RXP2"
$PN"AG24"100;
"G2_TXN2"
$PN"G24"58;
"G2_TXP4"
$PN"J26"68;
"G2_RXP1"
$PN"AC24"99;
"G2_TXN1"
$PN"J24"57;
"G2_TXP3"
$PN"L23"67;
"G2_RXP0"
$PN"AE24"98;
"G2_TXN0"
$PN"N24"56;
"G2_TXP2"
$PN"G23"66;
"G2_TXP1"
$PN"J23"64;
"G2_RXN15"
$PN"AF35"97;
"G2_RXP15"
$PN"AF36"96;
"G2_RXN13"
$PN"AB35"95;
"G2_RXP13"
$PN"AB36"123;
"G2_RXN11"
$PN"AA32"126;
"G2_RXP11"
$PN"AA33"127;
"G2_RXN9"
$PN"AE32"128;
"G2_RXP9"
$PN"AE33"129;
"G2_RXN14"
$PN"AD35"94;
"G2_RXP14"
$PN"AD36"93;
"G2_RXN12"
$PN"AG32"124;
"G2_RXP12"
$PN"AG33"125;
"G2_RXN10"
$PN"AC32"28;
"G2_RXP10"
$PN"AC33"29;
"G2_RXN8"
$PN"AG29"130;
"G2_RXP8"
$PN"AG30"131;
"G2_TXN15"
$PN"M36"27;
"G2_TXP15"
$PN"M35"79;
"G2_TXN13"
$PN"H36"55;
"G2_TXP13"
$PN"H35"78;
"G2_TXN11"
$PN"G33"54;
"G2_TXP11"
$PN"G32"76;
"G2_TXN9"
$PN"L30"53;
"G2_TXP9"
$PN"L29"75;
"G2_TXN14"
$PN"K36"52;
"G2_TXP14"
$PN"K35"77;
"G2_TXN12"
$PN"L33"51;
"G2_TXP12"
$PN"L32"74;
"G2_TXN10"
$PN"J33"50;
"G2_TXP10"
$PN"J32"73;
"G2_TXN8"
$PN"G30"49;
"G2_TXP8"
$PN"G29"72;
%"GENOA_SP5"
"14","(-4750,2200)","0","pure_quanta","I216";
;
LOCATION"U25"
$SEC"14"
CDS_SEC"14"
PART_TYPE"SMLF"
MATERIAL"IO"
VALUE"SOCKET6096_13568-001"
PART_NUMBER"DGA^6000030"
CDS_LIB"pure_quanta"
NEEDS_NO_SIZE"TRUE"
CDS_LMAN_SYM_OUTLINE"-1100,950,1100,-950";
"G3_RXN2||SATA22_RXN"
$PN"AN23"41;
"G3_TXN9||SATA31_TXN"
$PN"U30"87;
"G3_RXN12||SATA34_RXN"
$PN"AK35"117;
"G3_RXN15||SATA37_RXN"
$PN"AP35"112;
"G3_TXP5||SATA25_TXP"
$PN"N26"10;
"G3_RXN9||SATA31_RXN"
$PN"AL32"47;
"G3_TXP2||SATA22_TXP"
$PN"W23"22;
"G3_RXP2||SATA22_RXP"
$PN"AN24"42;
"G3_RXP5||SATA25_RXP"
$PN"AN27"32;
"G3_RXP14||SATA36_RXP"
$PN"AM36"115;
"G3_TXN4||SATA24_TXN"
$PN"R27"19;
"G3_TXN7||SATA27_TXN"
$PN"R30"16;
"G3_TXN10||SATA32_TXN"
$PN"R33"12;
"G3_TXN13||SATA35_TXN"
$PN"P36"86;
"G3_RXP11||SATA33_RXP"
$PN"AN33"109;
"G3_TXN1||SATA21_TXN"
$PN"R24"23;
"G3_TXP9||SATA31_TXP"
$PN"U29"26;
"G3_TXP15||SATA37_TXP"
$PN"V35"92;
"G3_RXN1||SATA21_RXN"
$PN"AJ23"43;
"G3_RXN4||SATA24_RXN"
$PN"AJ26"33;
"G3_RXN7||SATA27_RXN"
$PN"AJ29"121;
"G3_TXP12||SATA34_TXP"
$PN"U32"91;
"G3_RXP9||SATA31_RXP"
$PN"AL33"120;
"G3_TXP7||SATA27_TXP"
$PN"R29"25;
"G3_TXN8||SATA30_TXN"
$PN"N30"80;
"G3_RXN11||SATA33_RXN"
$PN"AN32"48;
"G3_RXN14||SATA36_RXN"
$PN"AM35"114;
"G3_TXP1||SATA21_TXP"
$PN"R23"31;
"G3_TXP4||SATA24_TXP"
$PN"R26"20;
"G3_RXP7||SATA27_RXP"
$PN"AJ30"122;
"G3_RXN8||SATA30_RXN"
$PN"AN29"46;
"G3_TXN12||SATA34_TXN"
$PN"U33"85;
"G3_TXN15||SATA37_TXN"
$PN"V36"84;
"G3_RXP1||SATA21_RXP"
$PN"AJ24"44;
"G3_RXP4||SATA24_RXP"
$PN"AJ27"34;
"G3_RXP10||SATA32_RXP"
$PN"AJ33"111;
"G3_RXP13||SATA35_RXP"
$PN"AH36"118;
"G3_TXN3||SATA23_TXN"
$PN"U27"9;
"G3_TXN6||SATA26_TXN"
$PN"W27"11;
"G3_RXN6||SATA26_RXN"
$PN"AL29"37;
"G3_TXN0||SATA20_TXN"
$PN"U24"24;
"G3_TXP8||SATA30_TXP"
$PN"N29"81;
"G3_TXP14||SATA36_TXP"
$PN"T35"90;
"G3_RXN0||SATA20_RXN"
$PN"AL23"45;
"G3_RXN3||SATA23_RXN"
$PN"AL26"39;
"G3_RXP8||SATA30_RXP"
$PN"AN30"14;
"G3_TXP11||SATA33_TXP"
$PN"N32"89;
"G3_RXN13||SATA35_RXN"
$PN"AH35"116;
"G3_TXP6||SATA26_TXP"
$PN"W26"18;
"G3_RXN10||SATA32_RXN"
$PN"AJ32"110;
"G3_TXP0||SATA20_TXP"
$PN"U23"30;
"G3_TXP3||SATA23_TXP"
$PN"U26"15;
"G3_RXP3||SATA23_RXP"
$PN"AL27"40;
"G3_RXP6||SATA26_RXP"
$PN"AL30"38;
"G3_RXP15||SATA37_RXP"
$PN"AP36"113;
"G3_TXN5||SATA25_TXN"
$PN"N27"17;
"G3_TXN11||SATA33_TXN"
$PN"N33"83;
"G3_TXN14||SATA36_TXN"
$PN"T36"82;
"G3_RXP0||SATA20_RXP"
$PN"AL24"36;
"G3_RXP12||SATA34_RXP"
$PN"AK36"119;
"G3_TXN2||SATA22_TXN"
$PN"W24"21;
"G3_RXN5||SATA25_RXN"
$PN"AN26"35;
"G3_TXP10||SATA32_TXP"
$PN"R32"13;
"G3_TXP13||SATA35_TXP"
$PN"P35"88;
%"TAP"
"6","(-2950,5775)","2","mstr_standard","I219";
;
BOM_COST"IO_SLOT"
CDS_LIB"mstr_standard"
BODY_TYPE"PLUMBING"
HDL_TAP"TRUE"
ROOM"RISER1";
"B \NAC \NWC"7;
"S \NAC"
BN"0"56;
%"TAP"
"6","(-2950,5675)","2","mstr_standard","I220";
;
CDS_LIB"mstr_standard"
BOM_COST"IO_SLOT"
BODY_TYPE"PLUMBING"
HDL_TAP"TRUE"
ROOM"RISER1";
"B \NAC \NWC"7;
"S \NAC"
BN"1"57;
%"TAP"
"6","(-3100,5825)","2","mstr_standard","I221";
;
CDS_LIB"mstr_standard"
BOM_COST"IO_SLOT"
BODY_TYPE"PLUMBING"
HDL_TAP"TRUE"
ROOM"RISER1";
"B \NAC \NWC"6;
"S \NAC"
BN"0"65;
%"TAP"
"6","(-3100,5725)","2","mstr_standard","I222";
;
CDS_LIB"mstr_standard"
BOM_COST"IO_SLOT"
BODY_TYPE"PLUMBING"
HDL_TAP"TRUE"
ROOM"RISER1";
"B \NAC \NWC"6;
"S \NAC"
BN"1"64;
%"TAP"
"6","(-2950,5575)","2","standard","I223";
;
CDS_LIB"standard"
BOM_COST"IO_SLOT"
BODY_TYPE"PLUMBING"
HDL_TAP"TRUE"
ROOM"RISER1";
"B \NAC \NWC"7;
"S \NAC"
BN"2"58;
%"TAP"
"6","(-2950,5475)","2","standard","I224";
;
CDS_LIB"standard"
BOM_COST"IO_SLOT"
BODY_TYPE"PLUMBING"
HDL_TAP"TRUE"
ROOM"RISER1";
"B \NAC \NWC"7;
"S \NAC"
BN"3"59;
%"TAP"
"6","(-3100,5625)","2","standard","I225";
;
CDS_LIB"standard"
BOM_COST"IO_SLOT"
BODY_TYPE"PLUMBING"
HDL_TAP"TRUE"
ROOM"RISER1";
"B \NAC \NWC"6;
"S \NAC"
BN"2"66;
%"TAP"
"6","(-3100,5525)","2","standard","I226";
;
CDS_LIB"standard"
BOM_COST"IO_SLOT"
BODY_TYPE"PLUMBING"
HDL_TAP"TRUE"
ROOM"RISER1";
"B \NAC \NWC"6;
"S \NAC"
BN"3"67;
%"TAP"
"6","(-3100,5425)","2","standard","I227";
;
CDS_LIB"standard"
BOM_COST"IO_SLOT"
BODY_TYPE"PLUMBING"
HDL_TAP"TRUE"
ROOM"RISER1";
"B \NAC \NWC"6;
"S \NAC"
BN"4"68;
%"TAP"
"6","(-2950,5275)","2","standard","I228";
;
CDS_LIB"standard"
BOM_COST"IO_SLOT"
BODY_TYPE"PLUMBING"
HDL_TAP"TRUE"
ROOM"RISER1";
"B \NAC \NWC"7;
"S \NAC"
BN"5"61;
%"TAP"
"6","(-2950,5375)","2","standard","I229";
;
CDS_LIB"standard"
BOM_COST"IO_SLOT"
BODY_TYPE"PLUMBING"
HDL_TAP"TRUE"
ROOM"RISER1";
"B \NAC \NWC"7;
"S \NAC"
BN"4"60;
%"TAP"
"6","(-2950,5175)","2","standard","I230";
;
CDS_LIB"standard"
BOM_COST"IO_SLOT"
BODY_TYPE"PLUMBING"
HDL_TAP"TRUE"
ROOM"RISER1";
"B \NAC \NWC"7;
"S \NAC"
BN"6"62;
%"TAP"
"6","(-3100,5125)","2","standard","I231";
;
CDS_LIB"standard"
BOM_COST"IO_SLOT"
BODY_TYPE"PLUMBING"
HDL_TAP"TRUE"
ROOM"RISER1";
"B \NAC \NWC"6;
"S \NAC"
BN"7"71;
%"TAP"
"6","(-3100,5325)","2","standard","I232";
;
CDS_LIB"standard"
BOM_COST"IO_SLOT"
BODY_TYPE"PLUMBING"
HDL_TAP"TRUE"
ROOM"RISER1";
"B \NAC \NWC"6;
"S \NAC"
BN"5"69;
%"TAP"
"6","(-3100,5225)","2","standard","I233";
;
CDS_LIB"standard"
BOM_COST"IO_SLOT"
BODY_TYPE"PLUMBING"
HDL_TAP"TRUE"
ROOM"RISER1";
"B \NAC \NWC"6;
"S \NAC"
BN"6"70;
%"TAP"
"6","(-2950,5075)","2","standard","I234";
;
CDS_LIB"standard"
BOM_COST"IO_SLOT"
BODY_TYPE"PLUMBING"
HDL_TAP"TRUE"
ROOM"RISER1";
"B \NAC \NWC"7;
"S \NAC"
BN"7"63;
%"TAP"
"6","(-2950,4875)","2","standard","I235";
;
CDS_LIB"standard"
BOM_COST"IO_SLOT"
BODY_TYPE"PLUMBING"
HDL_TAP"TRUE"
ROOM"RISER1";
"B \NAC \NWC"7;
"S \NAC"
BN"9"53;
%"TAP"
"6","(-2950,4975)","2","standard","I236";
;
CDS_LIB"standard"
BOM_COST"IO_SLOT"
BODY_TYPE"PLUMBING"
HDL_TAP"TRUE"
ROOM"RISER1";
"B \NAC \NWC"7;
"S \NAC"
BN"8"49;
%"TAP"
"6","(-3100,5025)","2","standard","I237";
;
CDS_LIB"standard"
BOM_COST"IO_SLOT"
BODY_TYPE"PLUMBING"
HDL_TAP"TRUE"
ROOM"RISER1";
"B \NAC \NWC"6;
"S \NAC"
BN"8"72;
%"TAP"
"6","(-3100,4925)","2","standard","I238";
;
CDS_LIB"standard"
BOM_COST"IO_SLOT"
BODY_TYPE"PLUMBING"
HDL_TAP"TRUE"
ROOM"RISER1";
"B \NAC \NWC"6;
"S \NAC"
BN"9"75;
%"TAP"
"6","(-2950,4775)","2","standard","I239";
;
CDS_LIB"standard"
BOM_COST"IO_SLOT"
BODY_TYPE"PLUMBING"
HDL_TAP"TRUE"
ROOM"RISER1";
"B \NAC \NWC"7;
"S \NAC"
BN"10"50;
%"TAP"
"6","(-2950,4675)","2","standard","I240";
;
CDS_LIB"standard"
BOM_COST"IO_SLOT"
BODY_TYPE"PLUMBING"
HDL_TAP"TRUE"
ROOM"RISER1";
"B \NAC \NWC"7;
"S \NAC"
BN"11"54;
%"TAP"
"6","(-3100,4625)","2","standard","I241";
;
CDS_LIB"standard"
BOM_COST"IO_SLOT"
BODY_TYPE"PLUMBING"
HDL_TAP"TRUE"
ROOM"RISER1";
"B \NAC \NWC"6;
"S \NAC"
BN"12"74;
%"TAP"
"6","(-3100,4825)","2","standard","I242";
;
CDS_LIB"standard"
BOM_COST"IO_SLOT"
BODY_TYPE"PLUMBING"
HDL_TAP"TRUE"
ROOM"RISER1";
"B \NAC \NWC"6;
"S \NAC"
BN"10"73;
%"TAP"
"6","(-3100,4725)","2","standard","I243";
;
CDS_LIB"standard"
BOM_COST"IO_SLOT"
BODY_TYPE"PLUMBING"
HDL_TAP"TRUE"
ROOM"RISER1";
"B \NAC \NWC"6;
"S \NAC"
BN"11"76;
%"TAP"
"6","(-2950,4575)","2","standard","I244";
;
CDS_LIB"standard"
BOM_COST"IO_SLOT"
BODY_TYPE"PLUMBING"
HDL_TAP"TRUE"
ROOM"RISER1";
"B \NAC \NWC"7;
"S \NAC"
BN"12"51;
%"TAP"
"6","(-2950,4375)","2","standard","I245";
;
BOM_COST"IO_SLOT"
CDS_LIB"standard"
BODY_TYPE"PLUMBING"
HDL_TAP"TRUE"
ROOM"RISER1";
"B \NAC \NWC"7;
"S \NAC"
BN"14"52;
%"TAP"
"6","(-2950,4475)","2","standard","I246";
;
CDS_LIB"standard"
BOM_COST"IO_SLOT"
BODY_TYPE"PLUMBING"
HDL_TAP"TRUE"
ROOM"RISER1";
"B \NAC \NWC"7;
"S \NAC"
BN"13"55;
%"TAP"
"6","(-3100,4425)","2","standard","I247";
;
CDS_LIB"standard"
BOM_COST"IO_SLOT"
BODY_TYPE"PLUMBING"
HDL_TAP"TRUE"
ROOM"RISER1";
"B \NAC \NWC"6;
"S \NAC"
BN"14"77;
%"TAP"
"6","(-3100,4525)","2","standard","I248";
;
CDS_LIB"standard"
BOM_COST"IO_SLOT"
BODY_TYPE"PLUMBING"
HDL_TAP"TRUE"
ROOM"RISER1";
"B \NAC \NWC"6;
"S \NAC"
BN"13"78;
%"TAP"
"6","(-2950,4275)","2","standard","I249";
;
CDS_LIB"standard"
BOM_COST"IO_SLOT"
BODY_TYPE"PLUMBING"
HDL_TAP"TRUE"
ROOM"RISER1";
"B \NAC \NWC"7;
"S \NAC"
BN"15"27;
%"TAP"
"6","(-3100,4325)","2","standard","I250";
;
CDS_LIB"standard"
BOM_COST"IO_SLOT"
BODY_TYPE"PLUMBING"
HDL_TAP"TRUE"
ROOM"RISER1";
"B \NAC \NWC"6;
"S \NAC"
BN"15"79;
%"TAP"
"6","(-6525,5825)","0","mstr_standard","I251";
;
CDS_LIB"mstr_standard"
BODY_TYPE"PLUMBING"
HDL_TAP"TRUE";
"B \NAC \NWC"1;
"S \NAC"
BN"0"98;
%"TAP"
"6","(-6525,5725)","0","mstr_standard","I252";
;
CDS_LIB"mstr_standard"
BODY_TYPE"PLUMBING"
HDL_TAP"TRUE";
"B \NAC \NWC"1;
"S \NAC"
BN"1"99;
%"TAP"
"6","(-6675,5775)","0","mstr_standard","I253";
;
CDS_LIB"mstr_standard"
BODY_TYPE"PLUMBING"
HDL_TAP"TRUE";
"B \NAC \NWC"2;
"S \NAC"
BN"0"101;
%"TAP"
"6","(-6675,5675)","0","mstr_standard","I254";
;
CDS_LIB"mstr_standard"
BODY_TYPE"PLUMBING"
HDL_TAP"TRUE";
"B \NAC \NWC"2;
"S \NAC"
BN"1"103;
%"TAP"
"6","(-6525,5525)","0","standard","I255";
;
CDS_LIB"standard"
BODY_TYPE"PLUMBING"
HDL_TAP"TRUE";
"B \NAC \NWC"1;
"S \NAC"
BN"3"102;
%"TAP"
"6","(-6525,5625)","0","mstr_standard","I256";
;
CDS_LIB"mstr_standard"
BODY_TYPE"PLUMBING"
HDL_TAP"TRUE";
"B \NAC \NWC"1;
"S \NAC"
BN"2"100;
%"TAP"
"6","(-6525,5425)","0","standard","I257";
;
CDS_LIB"standard"
BODY_TYPE"PLUMBING"
HDL_TAP"TRUE";
"B \NAC \NWC"1;
"S \NAC"
BN"4"104;
%"TAP"
"6","(-6675,5575)","0","standard","I258";
;
CDS_LIB"standard"
BODY_TYPE"PLUMBING"
HDL_TAP"TRUE";
"B \NAC \NWC"2;
"S \NAC"
BN"2"105;
%"TAP"
"6","(-6675,5475)","0","standard","I259";
;
CDS_LIB"standard"
BODY_TYPE"PLUMBING"
HDL_TAP"TRUE";
"B \NAC \NWC"2;
"S \NAC"
BN"3"107;
%"TAP"
"6","(-6525,5325)","0","standard","I260";
;
CDS_LIB"standard"
BODY_TYPE"PLUMBING"
HDL_TAP"TRUE";
"B \NAC \NWC"1;
"S \NAC"
BN"5"106;
%"TAP"
"6","(-6525,5225)","0","standard","I261";
;
CDS_LIB"standard"
BODY_TYPE"PLUMBING"
HDL_TAP"TRUE";
"B \NAC \NWC"1;
"S \NAC"
BN"6"135;
%"TAP"
"6","(-6525,5125)","0","standard","I262";
;
CDS_LIB"standard"
BODY_TYPE"PLUMBING"
HDL_TAP"TRUE";
"B \NAC \NWC"1;
"S \NAC"
BN"7"133;
%"TAP"
"6","(-6675,5275)","0","standard","I263";
;
CDS_LIB"standard"
BODY_TYPE"PLUMBING"
HDL_TAP"TRUE";
"B \NAC \NWC"2;
"S \NAC"
BN"5"136;
%"TAP"
"6","(-6675,5375)","0","standard","I264";
;
CDS_LIB"standard"
BODY_TYPE"PLUMBING"
HDL_TAP"TRUE";
"B \NAC \NWC"2;
"S \NAC"
BN"4"108;
%"TAP"
"6","(-6675,5175)","0","standard","I265";
;
CDS_LIB"standard"
BODY_TYPE"PLUMBING"
HDL_TAP"TRUE";
"B \NAC \NWC"2;
"S \NAC"
BN"6"134;
%"TAP"
"6","(-6525,5025)","0","standard","I266";
;
CDS_LIB"standard"
BODY_TYPE"PLUMBING"
HDL_TAP"TRUE";
"B \NAC \NWC"1;
"S \NAC"
BN"8"131;
%"TAP"
"6","(-6525,4925)","0","standard","I267";
;
CDS_LIB"standard"
BODY_TYPE"PLUMBING"
HDL_TAP"TRUE";
"B \NAC \NWC"1;
"S \NAC"
BN"9"129;
%"TAP"
"6","(-6675,5075)","0","standard","I268";
;
CDS_LIB"standard"
BODY_TYPE"PLUMBING"
HDL_TAP"TRUE";
"B \NAC \NWC"2;
"S \NAC"
BN"7"132;
%"TAP"
"6","(-6675,4975)","0","standard","I269";
;
CDS_LIB"standard"
BODY_TYPE"PLUMBING"
HDL_TAP"TRUE";
"B \NAC \NWC"2;
"S \NAC"
BN"8"130;
%"TAP"
"6","(-6675,4875)","0","standard","I270";
;
CDS_LIB"standard"
BODY_TYPE"PLUMBING"
HDL_TAP"TRUE";
"B \NAC \NWC"2;
"S \NAC"
BN"9"128;
%"TAP"
"6","(-6525,4825)","0","standard","I271";
;
CDS_LIB"standard"
BODY_TYPE"PLUMBING"
HDL_TAP"TRUE";
"B \NAC \NWC"1;
"S \NAC"
BN"10"29;
%"TAP"
"6","(-6525,4625)","0","standard","I272";
;
CDS_LIB"standard"
BODY_TYPE"PLUMBING"
HDL_TAP"TRUE";
"B \NAC \NWC"1;
"S \NAC"
BN"12"125;
%"TAP"
"6","(-6525,4725)","0","standard","I273";
;
CDS_LIB"standard"
BODY_TYPE"PLUMBING"
HDL_TAP"TRUE";
"B \NAC \NWC"1;
"S \NAC"
BN"11"127;
%"TAP"
"6","(-6675,4775)","0","standard","I274";
;
CDS_LIB"standard"
BODY_TYPE"PLUMBING"
HDL_TAP"TRUE";
"B \NAC \NWC"2;
"S \NAC"
BN"10"28;
%"TAP"
"6","(-6675,4675)","0","standard","I275";
;
CDS_LIB"standard"
BODY_TYPE"PLUMBING"
HDL_TAP"TRUE";
"B \NAC \NWC"2;
"S \NAC"
BN"11"126;
%"TAP"
"6","(-6525,4525)","0","standard","I276";
;
CDS_LIB"standard"
BODY_TYPE"PLUMBING"
HDL_TAP"TRUE";
"B \NAC \NWC"1;
"S \NAC"
BN"13"123;
%"TAP"
"6","(-6525,4425)","0","standard","I277";
;
CDS_LIB"standard"
BODY_TYPE"PLUMBING"
HDL_TAP"TRUE";
"B \NAC \NWC"1;
"S \NAC"
BN"14"93;
%"TAP"
"6","(-6675,4575)","0","standard","I278";
;
CDS_LIB"standard"
BODY_TYPE"PLUMBING"
HDL_TAP"TRUE";
"B \NAC \NWC"2;
"S \NAC"
BN"12"124;
%"TAP"
"6","(-6675,4475)","0","standard","I279";
;
CDS_LIB"standard"
BODY_TYPE"PLUMBING"
HDL_TAP"TRUE";
"B \NAC \NWC"2;
"S \NAC"
BN"13"95;
%"TAP"
"6","(-6675,4375)","0","standard","I280";
;
CDS_LIB"standard"
BODY_TYPE"PLUMBING"
HDL_TAP"TRUE";
"B \NAC \NWC"2;
"S \NAC"
BN"14"94;
%"TAP"
"6","(-6525,4325)","0","standard","I281";
;
CDS_LIB"standard"
BODY_TYPE"PLUMBING"
HDL_TAP"TRUE";
"B \NAC \NWC"1;
"S \NAC"
BN"15"96;
%"TAP"
"6","(-6675,4275)","0","standard","I282";
;
CDS_LIB"standard"
BODY_TYPE"PLUMBING"
HDL_TAP"TRUE";
"B \NAC \NWC"2;
"S \NAC"
BN"15"97;
%"TAP"
"6","(-3075,2650)","2","standard","I285";
;
CDS_LIB"standard"
BOM_COST"IO_SLOT"
BODY_TYPE"PLUMBING"
HDL_TAP"TRUE"
ROOM"RISER1";
"B \NAC \NWC"5;
"S \NAC"
BN"3"15;
%"TAP"
"6","(-2925,2600)","2","standard","I286";
;
CDS_LIB"standard"
BOM_COST"IO_SLOT"
BODY_TYPE"PLUMBING"
HDL_TAP"TRUE"
ROOM"RISER1";
"B \NAC \NWC"8;
"S \NAC"
BN"3"9;
%"TAP"
"6","(-2925,2500)","2","standard","I287";
;
CDS_LIB"standard"
BOM_COST"IO_SLOT"
BODY_TYPE"PLUMBING"
HDL_TAP"TRUE"
ROOM"RISER1";
"B \NAC \NWC"8;
"S \NAC"
BN"4"19;
%"TAP"
"6","(-2925,2400)","2","standard","I288";
;
CDS_LIB"standard"
BOM_COST"IO_SLOT"
BODY_TYPE"PLUMBING"
HDL_TAP"TRUE"
ROOM"RISER1";
"B \NAC \NWC"8;
"S \NAC"
BN"5"17;
%"TAP"
"6","(-2925,2300)","2","standard","I289";
;
CDS_LIB"standard"
BOM_COST"IO_SLOT"
BODY_TYPE"PLUMBING"
HDL_TAP"TRUE"
ROOM"RISER1";
"B \NAC \NWC"8;
"S \NAC"
BN"6"11;
%"TAP"
"6","(-2925,2900)","2","mstr_standard","I292";
;
BOM_COST"IO_SLOT"
CDS_LIB"mstr_standard"
BODY_TYPE"PLUMBING"
HDL_TAP"TRUE"
ROOM"RISER1";
"B \NAC \NWC"8;
"S \NAC"
BN"0"24;
%"TAP"
"6","(-3075,2850)","2","mstr_standard","I293";
;
CDS_LIB"mstr_standard"
BOM_COST"IO_SLOT"
BODY_TYPE"PLUMBING"
HDL_TAP"TRUE"
ROOM"RISER1";
"B \NAC \NWC"5;
"S \NAC"
BN"1"31;
%"TAP"
"6","(-3075,2950)","2","mstr_standard","I294";
;
CDS_LIB"mstr_standard"
BOM_COST"IO_SLOT"
BODY_TYPE"PLUMBING"
HDL_TAP"TRUE"
ROOM"RISER1";
"B \NAC \NWC"5;
"S \NAC"
BN"0"30;
%"TAP"
"6","(-2925,2700)","2","standard","I295";
;
CDS_LIB"standard"
BOM_COST"IO_SLOT"
BODY_TYPE"PLUMBING"
HDL_TAP"TRUE"
ROOM"RISER1";
"B \NAC \NWC"8;
"S \NAC"
BN"2"21;
%"TAP"
"6","(-2925,2800)","2","mstr_standard","I296";
;
CDS_LIB"mstr_standard"
BOM_COST"IO_SLOT"
BODY_TYPE"PLUMBING"
HDL_TAP"TRUE"
ROOM"RISER1";
"B \NAC \NWC"8;
"S \NAC"
BN"1"23;
%"TAP"
"6","(-3075,2750)","2","standard","I297";
;
CDS_LIB"standard"
BOM_COST"IO_SLOT"
BODY_TYPE"PLUMBING"
HDL_TAP"TRUE"
ROOM"RISER1";
"B \NAC \NWC"5;
"S \NAC"
BN"2"22;
%"TAP"
"6","(-3075,2350)","2","standard","I298";
;
CDS_LIB"standard"
BOM_COST"IO_SLOT"
BODY_TYPE"PLUMBING"
HDL_TAP"TRUE"
ROOM"RISER1";
"B \NAC \NWC"5;
"S \NAC"
BN"6"18;
%"TAP"
"6","(-3075,2550)","2","standard","I299";
;
CDS_LIB"standard"
BOM_COST"IO_SLOT"
BODY_TYPE"PLUMBING"
HDL_TAP"TRUE"
ROOM"RISER1";
"B \NAC \NWC"5;
"S \NAC"
BN"4"20;
%"TAP"
"6","(-3075,2450)","2","standard","I300";
;
CDS_LIB"standard"
BOM_COST"IO_SLOT"
BODY_TYPE"PLUMBING"
HDL_TAP"TRUE"
ROOM"RISER1";
"B \NAC \NWC"5;
"S \NAC"
BN"5"10;
%"TAP"
"6","(-2925,2200)","2","standard","I301";
;
CDS_LIB"standard"
BOM_COST"IO_SLOT"
BODY_TYPE"PLUMBING"
HDL_TAP"TRUE"
ROOM"RISER1";
"B \NAC \NWC"8;
"S \NAC"
BN"7"16;
%"TAP"
"6","(-2925,2100)","2","standard","I302";
;
CDS_LIB"standard"
BOM_COST"IO_SLOT"
BODY_TYPE"PLUMBING"
HDL_TAP"TRUE"
ROOM"RISER1";
"B \NAC \NWC"8;
"S \NAC"
BN"8"80;
%"TAP"
"6","(-3075,2250)","2","standard","I303";
;
CDS_LIB"standard"
BOM_COST"IO_SLOT"
BODY_TYPE"PLUMBING"
HDL_TAP"TRUE"
ROOM"RISER1";
"B \NAC \NWC"5;
"S \NAC"
BN"7"25;
%"TAP"
"6","(-3075,2150)","2","standard","I304";
;
CDS_LIB"standard"
BOM_COST"IO_SLOT"
BODY_TYPE"PLUMBING"
HDL_TAP"TRUE"
ROOM"RISER1";
"B \NAC \NWC"5;
"S \NAC"
BN"8"81;
%"TAP"
"6","(-3075,2050)","2","standard","I305";
;
CDS_LIB"standard"
BOM_COST"IO_SLOT"
BODY_TYPE"PLUMBING"
HDL_TAP"TRUE"
ROOM"RISER1";
"B \NAC \NWC"5;
"S \NAC"
BN"9"26;
%"TAP"
"6","(-2925,2000)","2","standard","I306";
;
CDS_LIB"standard"
BOM_COST"IO_SLOT"
BODY_TYPE"PLUMBING"
HDL_TAP"TRUE"
ROOM"RISER1";
"B \NAC \NWC"8;
"S \NAC"
BN"9"87;
%"TAP"
"6","(-2925,1800)","2","standard","I307";
;
CDS_LIB"standard"
BOM_COST"IO_SLOT"
BODY_TYPE"PLUMBING"
HDL_TAP"TRUE"
ROOM"RISER1";
"B \NAC \NWC"8;
"S \NAC"
BN"11"83;
%"TAP"
"6","(-2925,1900)","2","standard","I308";
;
CDS_LIB"standard"
BOM_COST"IO_SLOT"
BODY_TYPE"PLUMBING"
HDL_TAP"TRUE"
ROOM"RISER1";
"B \NAC \NWC"8;
"S \NAC"
BN"10"12;
%"TAP"
"6","(-3075,1950)","2","standard","I309";
;
CDS_LIB"standard"
BOM_COST"IO_SLOT"
BODY_TYPE"PLUMBING"
HDL_TAP"TRUE"
ROOM"RISER1";
"B \NAC \NWC"5;
"S \NAC"
BN"10"13;
%"TAP"
"6","(-3075,1850)","2","standard","I310";
;
CDS_LIB"standard"
BOM_COST"IO_SLOT"
BODY_TYPE"PLUMBING"
HDL_TAP"TRUE"
ROOM"RISER1";
"B \NAC \NWC"5;
"S \NAC"
BN"11"89;
%"TAP"
"6","(-2925,1700)","2","standard","I311";
;
CDS_LIB"standard"
BOM_COST"IO_SLOT"
BODY_TYPE"PLUMBING"
HDL_TAP"TRUE"
ROOM"RISER1";
"B \NAC \NWC"8;
"S \NAC"
BN"12"85;
%"TAP"
"6","(-2925,1600)","2","standard","I312";
;
CDS_LIB"standard"
BOM_COST"IO_SLOT"
BODY_TYPE"PLUMBING"
HDL_TAP"TRUE"
ROOM"RISER1";
"B \NAC \NWC"8;
"S \NAC"
BN"13"86;
%"TAP"
"6","(-3075,1650)","2","standard","I313";
;
CDS_LIB"standard"
BOM_COST"IO_SLOT"
BODY_TYPE"PLUMBING"
HDL_TAP"TRUE"
ROOM"RISER1";
"B \NAC \NWC"5;
"S \NAC"
BN"13"88;
%"TAP"
"6","(-3075,1750)","2","standard","I314";
;
CDS_LIB"standard"
BOM_COST"IO_SLOT"
BODY_TYPE"PLUMBING"
HDL_TAP"TRUE"
ROOM"RISER1";
"B \NAC \NWC"5;
"S \NAC"
BN"12"91;
%"TAP"
"6","(-3075,1550)","2","standard","I315";
;
CDS_LIB"standard"
BOM_COST"IO_SLOT"
BODY_TYPE"PLUMBING"
HDL_TAP"TRUE"
ROOM"RISER1";
"B \NAC \NWC"5;
"S \NAC"
BN"14"90;
%"TAP"
"6","(-2925,1500)","2","standard","I316";
;
BOM_COST"IO_SLOT"
CDS_LIB"standard"
BODY_TYPE"PLUMBING"
HDL_TAP"TRUE"
ROOM"RISER1";
"B \NAC \NWC"8;
"S \NAC"
BN"14"82;
%"TAP"
"6","(-2925,1400)","2","standard","I317";
;
CDS_LIB"standard"
BOM_COST"IO_SLOT"
BODY_TYPE"PLUMBING"
HDL_TAP"TRUE"
ROOM"RISER1";
"B \NAC \NWC"8;
"S \NAC"
BN"15"84;
%"TAP"
"6","(-3075,1450)","2","standard","I318";
;
CDS_LIB"standard"
BOM_COST"IO_SLOT"
BODY_TYPE"PLUMBING"
HDL_TAP"TRUE"
ROOM"RISER1";
"B \NAC \NWC"5;
"S \NAC"
BN"15"92;
%"TAP"
"6","(-6500,2950)","0","mstr_standard","I319";
;
CDS_LIB"mstr_standard"
BODY_TYPE"PLUMBING"
HDL_TAP"TRUE";
"B \NAC \NWC"3;
"S \NAC"
BN"0"36;
%"TAP"
"6","(-6500,2850)","0","mstr_standard","I320";
;
CDS_LIB"mstr_standard"
BODY_TYPE"PLUMBING"
HDL_TAP"TRUE";
"B \NAC \NWC"3;
"S \NAC"
BN"1"44;
%"TAP"
"6","(-6650,2900)","0","mstr_standard","I321";
;
CDS_LIB"mstr_standard"
BODY_TYPE"PLUMBING"
HDL_TAP"TRUE";
"B \NAC \NWC"4;
"S \NAC"
BN"0"45;
%"TAP"
"6","(-6500,2750)","0","mstr_standard","I322";
;
CDS_LIB"mstr_standard"
BODY_TYPE"PLUMBING"
HDL_TAP"TRUE";
"B \NAC \NWC"3;
"S \NAC"
BN"2"42;
%"TAP"
"6","(-6500,2650)","0","standard","I323";
;
CDS_LIB"standard"
BODY_TYPE"PLUMBING"
HDL_TAP"TRUE";
"B \NAC \NWC"3;
"S \NAC"
BN"3"40;
%"TAP"
"6","(-6650,2800)","0","mstr_standard","I324";
;
CDS_LIB"mstr_standard"
BODY_TYPE"PLUMBING"
HDL_TAP"TRUE";
"B \NAC \NWC"4;
"S \NAC"
BN"1"43;
%"TAP"
"6","(-6650,2700)","0","standard","I325";
;
CDS_LIB"standard"
BODY_TYPE"PLUMBING"
HDL_TAP"TRUE";
"B \NAC \NWC"4;
"S \NAC"
BN"2"41;
%"TAP"
"6","(-6650,2600)","0","standard","I326";
;
CDS_LIB"standard"
BODY_TYPE"PLUMBING"
HDL_TAP"TRUE";
"B \NAC \NWC"4;
"S \NAC"
BN"3"39;
%"TAP"
"6","(-6500,2550)","0","standard","I327";
;
CDS_LIB"standard"
BODY_TYPE"PLUMBING"
HDL_TAP"TRUE";
"B \NAC \NWC"3;
"S \NAC"
BN"4"34;
%"TAP"
"6","(-6500,2450)","0","standard","I328";
;
CDS_LIB"standard"
BODY_TYPE"PLUMBING"
HDL_TAP"TRUE";
"B \NAC \NWC"3;
"S \NAC"
BN"5"32;
%"TAP"
"6","(-6500,2350)","0","standard","I329";
;
CDS_LIB"standard"
BODY_TYPE"PLUMBING"
HDL_TAP"TRUE";
"B \NAC \NWC"3;
"S \NAC"
BN"6"38;
%"TAP"
"6","(-6650,2500)","0","standard","I330";
;
CDS_LIB"standard"
BODY_TYPE"PLUMBING"
HDL_TAP"TRUE";
"B \NAC \NWC"4;
"S \NAC"
BN"4"33;
%"TAP"
"6","(-6650,2400)","0","standard","I331";
;
CDS_LIB"standard"
BODY_TYPE"PLUMBING"
HDL_TAP"TRUE";
"B \NAC \NWC"4;
"S \NAC"
BN"5"35;
%"TAP"
"6","(-6500,2250)","0","standard","I332";
;
CDS_LIB"standard"
BODY_TYPE"PLUMBING"
HDL_TAP"TRUE";
"B \NAC \NWC"3;
"S \NAC"
BN"7"122;
%"TAP"
"6","(-6500,2150)","0","standard","I333";
;
CDS_LIB"standard"
BODY_TYPE"PLUMBING"
HDL_TAP"TRUE";
"B \NAC \NWC"3;
"S \NAC"
BN"8"14;
%"TAP"
"6","(-6500,2050)","0","standard","I334";
;
CDS_LIB"standard"
BODY_TYPE"PLUMBING"
HDL_TAP"TRUE";
"B \NAC \NWC"3;
"S \NAC"
BN"9"120;
%"TAP"
"6","(-6650,2300)","0","standard","I335";
;
CDS_LIB"standard"
BODY_TYPE"PLUMBING"
HDL_TAP"TRUE";
"B \NAC \NWC"4;
"S \NAC"
BN"6"37;
%"TAP"
"6","(-6650,2200)","0","standard","I336";
;
CDS_LIB"standard"
BODY_TYPE"PLUMBING"
HDL_TAP"TRUE";
"B \NAC \NWC"4;
"S \NAC"
BN"7"121;
%"TAP"
"6","(-6650,2100)","0","standard","I337";
;
CDS_LIB"standard"
BODY_TYPE"PLUMBING"
HDL_TAP"TRUE";
"B \NAC \NWC"4;
"S \NAC"
BN"8"46;
%"TAP"
"6","(-6500,1950)","0","standard","I340";
;
CDS_LIB"standard"
BODY_TYPE"PLUMBING"
HDL_TAP"TRUE";
"B \NAC \NWC"3;
"S \NAC"
BN"10"111;
%"TAP"
"6","(-6500,1850)","0","standard","I341";
;
CDS_LIB"standard"
BODY_TYPE"PLUMBING"
HDL_TAP"TRUE";
"B \NAC \NWC"3;
"S \NAC"
BN"11"109;
%"TAP"
"6","(-6650,2000)","0","standard","I342";
;
CDS_LIB"standard"
BODY_TYPE"PLUMBING"
HDL_TAP"TRUE";
"B \NAC \NWC"4;
"S \NAC"
BN"9"47;
%"TAP"
"6","(-6650,1900)","0","standard","I343";
;
CDS_LIB"standard"
BODY_TYPE"PLUMBING"
HDL_TAP"TRUE";
"B \NAC \NWC"4;
"S \NAC"
BN"10"110;
%"TAP"
"6","(-6650,1800)","0","standard","I344";
;
CDS_LIB"standard"
BODY_TYPE"PLUMBING"
HDL_TAP"TRUE";
"B \NAC \NWC"4;
"S \NAC"
BN"11"48;
%"TAP"
"6","(-6500,1650)","0","standard","I345";
;
CDS_LIB"standard"
BODY_TYPE"PLUMBING"
HDL_TAP"TRUE";
"B \NAC \NWC"3;
"S \NAC"
BN"13"118;
%"TAP"
"6","(-6500,1750)","0","standard","I346";
;
CDS_LIB"standard"
BODY_TYPE"PLUMBING"
HDL_TAP"TRUE";
"B \NAC \NWC"3;
"S \NAC"
BN"12"119;
%"TAP"
"6","(-6500,1550)","0","standard","I347";
;
CDS_LIB"standard"
BODY_TYPE"PLUMBING"
HDL_TAP"TRUE";
"B \NAC \NWC"3;
"S \NAC"
BN"14"115;
%"TAP"
"6","(-6650,1700)","0","standard","I348";
;
CDS_LIB"standard"
BODY_TYPE"PLUMBING"
HDL_TAP"TRUE";
"B \NAC \NWC"4;
"S \NAC"
BN"12"117;
%"TAP"
"6","(-6650,1600)","0","standard","I349";
;
CDS_LIB"standard"
BODY_TYPE"PLUMBING"
HDL_TAP"TRUE";
"B \NAC \NWC"4;
"S \NAC"
BN"13"116;
%"TAP"
"6","(-6500,1450)","0","standard","I350";
;
CDS_LIB"standard"
BODY_TYPE"PLUMBING"
HDL_TAP"TRUE";
"B \NAC \NWC"3;
"S \NAC"
BN"15"113;
%"TAP"
"6","(-6650,1500)","0","standard","I351";
;
CDS_LIB"standard"
BODY_TYPE"PLUMBING"
HDL_TAP"TRUE";
"B \NAC \NWC"4;
"S \NAC"
BN"14"114;
%"TAP"
"6","(-6650,1400)","0","standard","I352";
;
CDS_LIB"standard"
BODY_TYPE"PLUMBING"
HDL_TAP"TRUE";
"B \NAC \NWC"4;
"S \NAC"
BN"15"112;
END.
